(kicad_pcb
	(version 20260206)
	(generator "pcbnew")
	(generator_version "10.0")
	(general
		(thickness 1.6)
		(legacy_teardrops no)
	)
	(paper "A4")
	(title_block
		(title "timecard-production-celestica-r4006 — R4006-B0001-02_R01.brd")
		(comment 1 "Time Appliance Project (Time Card) / footprints 101-104 of 1113")
	)
	(layers
		(0 "F.Cu" signal "TOP")
		(4 "In1.Cu" signal "L02_GND1")
		(6 "In2.Cu" signal "L03_SIG1")
		(8 "In3.Cu" signal "L04_GND2")
		(10 "In4.Cu" signal "L05_VCC1")
		(12 "In5.Cu" signal "L06_VCC2")
		(14 "In6.Cu" signal "L07_GND3")
		(16 "In7.Cu" signal "L08_SIG2")
		(18 "In8.Cu" signal "L09_GND4")
		(2 "B.Cu" signal "BOTTOM")
		(9 "F.Adhes" user "F.Adhesive")
		(11 "B.Adhes" user "B.Adhesive")
		(13 "F.Paste" user "Package Geometry/Pastemask Top")
		(15 "B.Paste" user "Package Geometry/Pastemask Bottom")
		(5 "F.SilkS" user "Ref Des/Silkscreen Top")
		(7 "B.SilkS" user "Ref Des/Silkscreen Bottom")
		(1 "F.Mask" user "Board Geometry/Soldermask Top")
		(3 "B.Mask" user "Board Geometry/Soldermask Bottom")
		(17 "Dwgs.User" user "User.Drawings")
		(19 "Cmts.User" user "User.Comments")
		(21 "Eco1.User" user "User.Eco1")
		(23 "Eco2.User" user "User.Eco2")
		(25 "Edge.Cuts" user "Board Geometry/Outline")
		(27 "Margin" user)
		(31 "F.CrtYd" user "Package Geometry/Place Bound Top")
		(29 "B.CrtYd" user "Package Geometry/Place Bound Bottom")
		(35 "F.Fab" user "Ref Des/Assembly Top")
		(33 "B.Fab" user "Ref Des/Assembly Bottom")
	)
	(footprint ""
		(layer "F.Cu")
		(at 85.979 -54.229 180)
		(property "Reference" "TP61"
			(at 0.5842 -1.56337 0)
			(unlocked yes)
			(layer "F.SilkS")
			(effects
				(font
					(size 0.7874 0.5842)
					(thickness 0.1524)
				)
				(justify left)
			)
		)
		(property "Value" ""
			(at 0 0 180)
			(layer "F.Fab")
			(effects
				(font
					(size 1.27 1.27)
				)
			)
		)
		(property "Device Type" "TP_PIONT-TP010CT020B030_PTH-TPA"
			(at -1.341882 0.996696 180)
			(unlocked yes)
			(layer "F.Fab")
			(hide yes)
			(effects
				(font
					(size 0.7874 0.5842)
					(thickness 0.1524)
				)
				(justify left)
			)
		)
		(duplicate_pad_numbers_are_jumpers no)
		(fp_poly
			(pts
				(arc
					(start -0.889 0)
					(mid 0.889 0)
					(end -0.889 0)
				)
			)
			(stroke
				(width 0)
				(type default)
			)
			(fill no)
			(layer "B.CrtYd")
		)
		(fp_poly
			(pts
				(arc
					(start -0.889 0)
					(mid 0.889 0)
					(end -0.889 0)
				)
			)
			(stroke
				(width 0)
				(type default)
			)
			(fill no)
			(layer "F.CrtYd")
		)
		(pad "1" thru_hole circle
			(at 0 0 180)
			(size 0.508 0.508)
			(drill 0.254)
			(layers "*.Cu" "*.Mask")
			(remove_unused_layers no)
			(net "UNNAMED_9_BNO080LGA28_I29_HCS")
			(clearance 0.1016)
			(padstack
				(mode front_inner_back)
				(layer "Inner"
					(shape circle)
					(size 0.508 0.508)
					(clearance 0.1016)
				)
				(layer "B.Cu"
					(shape circle)
					(size 0.762 0.762)
					(clearance -0.0254)
				)
			)
		)
	)
	(footprint ""
		(layer "F.Cu")
		(at 92.583 -37.338 180)
		(property "Reference" "L34"
			(at 1.2065 -1.43637 0)
			(unlocked yes)
			(layer "F.SilkS")
			(effects
				(font
					(size 0.7874 0.5842)
					(thickness 0.1524)
				)
				(justify left)
			)
		)
		(property "Value" "VAL*"
			(at -0.9398 3.70967 180)
			(unlocked yes)
			(layer "F.Fab")
			(hide yes)
			(effects
				(font
					(size 0.7874 0.5842)
					(thickness 0.1524)
				)
				(justify left)
			)
		)
		(property "Device Type" "FERRITEBEAD-G191-10100-01,120OA"
			(at -0.9906 1.22047 180)
			(unlocked yes)
			(layer "F.Fab")
			(hide yes)
			(effects
				(font
					(size 0.7874 0.5842)
					(thickness 0.1524)
				)
				(justify left)
			)
		)
		(property "User Part Number" "PARTNUM*"
			(at -2.54 2.46507 180)
			(unlocked yes)
			(layer "Cmts.User")
			(hide yes)
			(effects
				(font
					(size 0.7874 0.5842)
					(thickness 0.1524)
				)
				(justify left)
			)
		)
		(property "Tolerance" "TOL*"
			(at -0.9906 5.00507 180)
			(unlocked yes)
			(layer "Cmts.User")
			(hide yes)
			(effects
				(font
					(size 0.7874 0.5842)
					(thickness 0.1524)
				)
				(justify left)
			)
		)
		(duplicate_pad_numbers_are_jumpers no)
		(fp_line
			(start 1.3208 0.7112)
			(end -1.3208 0.7112)
			(stroke
				(width 0.1)
				(type default)
			)
			(layer "F.SilkS")
		)
		(fp_line
			(start 1.3208 -0.7112)
			(end 1.3208 0.7112)
			(stroke
				(width 0.1)
				(type default)
			)
			(layer "F.SilkS")
		)
		(fp_line
			(start -1.3208 0.7112)
			(end -1.3208 -0.7112)
			(stroke
				(width 0.1)
				(type default)
			)
			(layer "F.SilkS")
		)
		(fp_line
			(start -1.3208 -0.7112)
			(end 1.3208 -0.7112)
			(stroke
				(width 0.1)
				(type default)
			)
			(layer "F.SilkS")
		)
		(fp_rect
			(start -1.3208 0.7112)
			(end 1.3208 -0.7112)
			(stroke
				(width 0)
				(type default)
			)
			(fill no)
			(layer "F.CrtYd")
		)
		(fp_line
			(start 0.8128 0.4572)
			(end -0.8128 0.4572)
			(stroke
				(width 0.1)
				(type default)
			)
			(layer "F.Fab")
		)
		(fp_line
			(start 0.8128 -0.4572)
			(end 0.8128 0.4572)
			(stroke
				(width 0.1)
				(type default)
			)
			(layer "F.Fab")
		)
		(fp_line
			(start -0.8128 0.4572)
			(end -0.8128 -0.4572)
			(stroke
				(width 0.1)
				(type default)
			)
			(layer "F.Fab")
		)
		(fp_line
			(start -0.8128 -0.4572)
			(end 0.8128 -0.4572)
			(stroke
				(width 0.1)
				(type default)
			)
			(layer "F.Fab")
		)
		(pad "1" smd rect
			(at -0.6858 0 180)
			(size 0.762 0.8636)
			(layers "F.Cu" "F.Mask" "F.Paste")
			(net "XP1R0V_FPGA_MGTAVCC")
		)
		(pad "2" smd rect
			(at 0.6858 0 180)
			(size 0.762 0.8636)
			(layers "F.Cu" "F.Mask" "F.Paste")
			(net "XP1R0V_FPGA")
		)
		(zone
			(layer "F.Cu")
			(hatch none 0.5)
			(connect_pads
				(clearance 0)
			)
			(min_thickness 0.25)
			(keepout
				(tracks not_allowed)
				(vias allowed)
				(pads allowed)
				(copperpour not_allowed)
				(footprints allowed)
			)
			(placement
				(enabled no)
				(sheetname "")
			)
			(fill
				(thermal_gap 0.5)
				(thermal_bridge_width 0.5)
				(island_removal_mode 0)
			)
			(polygon
				(pts
					(xy 92.7354 -37.7952) (xy 92.4306 -37.7952) (xy 92.4306 -36.8808) (xy 92.7354 -36.8808)
				)
			)
		)
		(zone
			(layer "F.Cu")
			(hatch none 0.5)
			(connect_pads
				(clearance 0)
			)
			(min_thickness 0.25)
			(keepout
				(tracks allowed)
				(vias not_allowed)
				(pads allowed)
				(copperpour not_allowed)
				(footprints allowed)
			)
			(placement
				(enabled no)
				(sheetname "")
			)
			(fill
				(thermal_gap 0.5)
				(thermal_bridge_width 0.5)
				(island_removal_mode 0)
			)
			(polygon
				(pts
					(xy 92.7354 -37.7952) (xy 92.4306 -37.7952) (xy 92.4306 -36.8808) (xy 92.7354 -36.8808)
				)
			)
		)
	)
	(footprint ""
		(layer "F.Cu")
		(at 86.106 -58.7756)
		(property "Reference" "U29"
			(at -3.00863 0.1016 90)
			(unlocked yes)
			(layer "F.SilkS")
			(effects
				(font
					(size 0.7874 0.5842)
					(thickness 0.1524)
				)
			)
		)
		(property "Value" ""
			(at 0 0 0)
			(layer "F.Fab")
			(effects
				(font
					(size 1.27 1.27)
				)
			)
		)
		(property "Device Type" "BNO080_LGA_28-A246-00002-FB,BNA"
			(at 0.040894 5.13842 0)
			(unlocked yes)
			(layer "F.Fab")
			(hide yes)
			(effects
				(font
					(size 0.7874 0.5842)
					(thickness 0.1524)
				)
			)
		)
		(property "User Part Number" "PARTNUM*"
			(at 0.040894 6.33222 0)
			(unlocked yes)
			(layer "Cmts.User")
			(hide yes)
			(effects
				(font
					(size 0.7874 0.5842)
					(thickness 0.1524)
				)
			)
		)
		(duplicate_pad_numbers_are_jumpers no)
		(fp_line
			(start -2.159508 -2.858516)
			(end 2.159508 -2.858516)
			(stroke
				(width 0.1)
				(type default)
			)
			(layer "F.SilkS")
		)
		(fp_line
			(start -2.159508 2.858516)
			(end -2.159508 -2.858516)
			(stroke
				(width 0.1)
				(type default)
			)
			(layer "F.SilkS")
		)
		(fp_line
			(start 2.159508 -2.858516)
			(end 2.159508 2.858516)
			(stroke
				(width 0.1)
				(type default)
			)
			(layer "F.SilkS")
		)
		(fp_line
			(start 2.159508 2.858516)
			(end -2.159508 2.858516)
			(stroke
				(width 0.1)
				(type default)
			)
			(layer "F.SilkS")
		)
		(fp_poly
			(pts
				(arc
					(start 3.302 -3.0734)
					(mid 2.286 -3.0734)
					(end 3.302 -3.0734)
				)
			)
			(stroke
				(width 0)
				(type default)
			)
			(fill yes)
			(layer "F.SilkS")
		)
		(fp_rect
			(start -2.413508 3.112516)
			(end 2.413508 -3.112516)
			(stroke
				(width 0)
				(type default)
			)
			(fill no)
			(layer "F.CrtYd")
		)
		(fp_line
			(start -1.89992 -2.599944)
			(end 1.89992 -2.599944)
			(stroke
				(width 0.1)
				(type default)
			)
			(layer "F.Fab")
		)
		(fp_line
			(start -1.89992 2.599944)
			(end -1.89992 -2.599944)
			(stroke
				(width 0.1)
				(type default)
			)
			(layer "F.Fab")
		)
		(fp_line
			(start 1.89992 -2.599944)
			(end 1.89992 2.599944)
			(stroke
				(width 0.1)
				(type default)
			)
			(layer "F.Fab")
		)
		(fp_line
			(start 1.89992 2.599944)
			(end -1.89992 2.599944)
			(stroke
				(width 0.1)
				(type default)
			)
			(layer "F.Fab")
		)
		(fp_poly
			(pts
				(arc
					(start 3.837686 -2.743962)
					(mid 2.821686 -2.743962)
					(end 3.837686 -2.743962)
				)
			)
			(stroke
				(width 0)
				(type default)
			)
			(fill yes)
			(layer "F.Fab")
		)
		(fp_text user "6"
			(at -2.509012 -2.331466 0)
			(unlocked yes)
			(layer "F.SilkS")
			(effects
				(font
					(size 0.635 0.4064)
					(thickness 0.1524)
				)
				(justify right)
			)
		)
		(fp_text user "15"
			(at -2.3114 2.03835 0)
			(unlocked yes)
			(layer "F.SilkS")
			(effects
				(font
					(size 0.635 0.4064)
					(thickness 0.1524)
				)
				(justify right)
			)
		)
		(fp_text user "5"
			(at -0.913638 -3.423666 0)
			(unlocked yes)
			(layer "F.SilkS")
			(effects
				(font
					(size 0.635 0.4064)
					(thickness 0.1524)
				)
			)
		)
		(fp_text user "2"
			(at 0.818134 -3.491738 0)
			(unlocked yes)
			(layer "F.SilkS")
			(effects
				(font
					(size 0.635 0.4064)
					(thickness 0.1524)
				)
			)
		)
		(fp_text user "28"
			(at 2.3114 -2.02565 0)
			(unlocked yes)
			(layer "F.SilkS")
			(effects
				(font
					(size 0.635 0.4064)
					(thickness 0.1524)
				)
				(justify left)
			)
		)
		(fp_text user "20"
			(at 2.413508 1.964182 0)
			(unlocked yes)
			(layer "F.SilkS")
			(effects
				(font
					(size 0.635 0.4064)
					(thickness 0.1524)
				)
				(justify left)
			)
		)
		(fp_text user "6"
			(at -2.509012 -2.400046 0)
			(unlocked yes)
			(layer "F.Fab")
			(effects
				(font
					(size 0.7874 0.5842)
					(thickness 0.1524)
				)
				(justify right)
			)
		)
		(fp_text user "15"
			(at -2.454148 2.372106 0)
			(unlocked yes)
			(layer "F.Fab")
			(effects
				(font
					(size 0.7874 0.5842)
					(thickness 0.1524)
				)
				(justify right)
			)
		)
		(fp_text user "5"
			(at -0.913638 -3.238246 0)
			(unlocked yes)
			(layer "F.Fab")
			(effects
				(font
					(size 0.7874 0.5842)
					(thickness 0.1524)
				)
			)
		)
		(fp_text user "16"
			(at -0.60071 3.35788 0)
			(unlocked yes)
			(layer "F.Fab")
			(effects
				(font
					(size 0.7874 0.5842)
					(thickness 0.1524)
				)
			)
		)
		(fp_text user "2"
			(at 0.818134 -3.306318 0)
			(unlocked yes)
			(layer "F.Fab")
			(effects
				(font
					(size 0.7874 0.5842)
					(thickness 0.1524)
				)
			)
		)
		(fp_text user "19"
			(at 1.36271 3.316986 0)
			(unlocked yes)
			(layer "F.Fab")
			(effects
				(font
					(size 0.7874 0.5842)
					(thickness 0.1524)
				)
			)
		)
		(fp_text user "28"
			(at 2.372868 -1.668526 0)
			(unlocked yes)
			(layer "F.Fab")
			(effects
				(font
					(size 0.7874 0.5842)
					(thickness 0.1524)
				)
				(justify left)
			)
		)
		(fp_text user "20"
			(at 2.413508 1.895602 0)
			(unlocked yes)
			(layer "F.Fab")
			(effects
				(font
					(size 0.7874 0.5842)
					(thickness 0.1524)
				)
				(justify left)
			)
		)
		(pad "1" smd rect
			(at 1.562608 -2.249932)
			(size 0.6858 0.254)
			(layers "F.Cu" "F.Mask" "F.Paste")
			(net "Net_782")
		)
		(pad "2" smd rect
			(at 0.750062 -2.312416)
			(size 0.254 0.5842)
			(layers "F.Cu" "F.Mask" "F.Paste")
			(net "SG")
		)
		(pad "3" smd rect
			(at 0.249936 -2.312416)
			(size 0.254 0.5842)
			(layers "F.Cu" "F.Mask" "F.Paste")
			(net "VDD_BNO085")
		)
		(pad "4" smd rect
			(at -0.249936 -2.312416)
			(size 0.254 0.5842)
			(layers "F.Cu" "F.Mask" "F.Paste")
			(net "R_BNO080_BOOT_N")
		)
		(pad "5" smd rect
			(at -0.750062 -2.312416)
			(size 0.254 0.5842)
			(layers "F.Cu" "F.Mask" "F.Paste")
			(net "UNNAMED_9_BNO080LGA28_I29_PS1")
		)
		(pad "6" smd rect
			(at -1.562608 -2.249932)
			(size 0.6858 0.254)
			(layers "F.Cu" "F.Mask" "F.Paste")
			(net "UNNAMED_9_BNO080LGA28_I29_PS0")
		)
		(pad "7" smd rect
			(at -1.562608 -1.75006)
			(size 0.6858 0.254)
			(layers "F.Cu" "F.Mask" "F.Paste")
			(net "Net_781")
		)
		(pad "8" smd rect
			(at -1.562608 -1.249934)
			(size 0.6858 0.254)
			(layers "F.Cu" "F.Mask" "F.Paste")
			(net "Net_780")
		)
		(pad "9" smd rect
			(at -1.562608 -0.750062)
			(size 0.6858 0.254)
			(layers "F.Cu" "F.Mask" "F.Paste")
			(net "UNNAMED_9_BNO080LGA28_I29_CAP")
		)
		(pad "10" smd rect
			(at -1.562608 -0.249936)
			(size 0.6858 0.254)
			(layers "F.Cu" "F.Mask" "F.Paste")
			(net "UNNAMED_9_BNO080LGA28_I29_CLKSE")
		)
		(pad "11" smd rect
			(at -1.562608 0.249936)
			(size 0.6858 0.254)
			(layers "F.Cu" "F.Mask" "F.Paste")
			(net "R_BNO080_RST_N")
		)
		(pad "12" smd rect
			(at -1.562608 0.750062)
			(size 0.6858 0.254)
			(layers "F.Cu" "F.Mask" "F.Paste")
			(net "Net_779")
		)
		(pad "13" smd rect
			(at -1.562608 1.249934)
			(size 0.6858 0.254)
			(layers "F.Cu" "F.Mask" "F.Paste")
			(net "Net_778")
		)
		(pad "14" smd rect
			(at -1.562608 1.75006)
			(size 0.6858 0.254)
			(layers "F.Cu" "F.Mask" "F.Paste")
			(net "R_BNO080_INT_N")
		)
		(pad "15" smd rect
			(at -1.562608 2.249932)
			(size 0.6858 0.254)
			(layers "F.Cu" "F.Mask" "F.Paste")
			(net "R_BNO080_EVN_SCL")
		)
		(pad "16" smd rect
			(at -0.750062 2.312416)
			(size 0.254 0.5842)
			(layers "F.Cu" "F.Mask" "F.Paste")
			(net "R_BNO080_EVN_SDA")
		)
		(pad "17" smd rect
			(at -0.249936 2.312416)
			(size 0.254 0.5842)
			(layers "F.Cu" "F.Mask" "F.Paste")
			(net "BNO080_SA0")
		)
		(pad "18" smd rect
			(at 0.249936 2.312416)
			(size 0.254 0.5842)
			(layers "F.Cu" "F.Mask" "F.Paste")
			(net "UNNAMED_9_BNO080LGA28_I29_HCS")
		)
		(pad "19" smd rect
			(at 0.750062 2.312416)
			(size 0.254 0.5842)
			(layers "F.Cu" "F.Mask" "F.Paste")
			(net "R_BNO080_I2C_SCL")
		)
		(pad "20" smd rect
			(at 1.562608 2.249932)
			(size 0.6858 0.254)
			(layers "F.Cu" "F.Mask" "F.Paste")
			(net "R_BNO080_I2C_SDA")
		)
		(pad "21" smd rect
			(at 1.562608 1.75006)
			(size 0.6858 0.254)
			(layers "F.Cu" "F.Mask" "F.Paste")
			(net "Net_777")
		)
		(pad "22" smd rect
			(at 1.562608 1.249934)
			(size 0.6858 0.254)
			(layers "F.Cu" "F.Mask" "F.Paste")
			(net "Net_776")
		)
		(pad "23" smd rect
			(at 1.562608 0.750062)
			(size 0.6858 0.254)
			(layers "F.Cu" "F.Mask" "F.Paste")
			(net "Net_775")
		)
		(pad "24" smd rect
			(at 1.562608 0.249936)
			(size 0.6858 0.254)
			(layers "F.Cu" "F.Mask" "F.Paste")
			(net "Net_774")
		)
		(pad "25" smd rect
			(at 1.562608 -0.249936)
			(size 0.6858 0.254)
			(layers "F.Cu" "F.Mask" "F.Paste")
			(net "SG")
		)
		(pad "26" smd rect
			(at 1.562608 -0.750062)
			(size 0.6858 0.254)
			(layers "F.Cu" "F.Mask" "F.Paste")
			(net "UNNAMED_9_BNO080LGA28_I29_XOUT3")
		)
		(pad "27" smd rect
			(at 1.562608 -1.249934)
			(size 0.6858 0.254)
			(layers "F.Cu" "F.Mask" "F.Paste")
			(net "UNNAMED_9_CAPACITOR_I17_1")
		)
		(pad "28" smd rect
			(at 1.562608 -1.75006)
			(size 0.6858 0.254)
			(layers "F.Cu" "F.Mask" "F.Paste")
			(net "VDD_BNO085")
		)
	)
	(footprint ""
		(layer "F.Cu")
		(at 20.32 -26.67 180)
		(property "Reference" "R388"
			(at -3.429 -0.67437 0)
			(unlocked yes)
			(layer "F.SilkS")
			(effects
				(font
					(size 0.7874 0.5842)
					(thickness 0.1524)
				)
			)
		)
		(property "Value" "VAL*"
			(at 0.02032 2.13233 180)
			(unlocked yes)
			(layer "F.Fab")
			(hide yes)
			(effects
				(font
					(size 0.7874 0.5842)
					(thickness 0.1524)
				)
			)
		)
		(property "Tolerance" "TOL*"
			(at 0.044704 3.05435 180)
			(unlocked yes)
			(layer "Cmts.User")
			(hide yes)
			(effects
				(font
					(size 0.7874 0.5842)
					(thickness 0.1524)
				)
			)
		)
		(property "User Part Number" "PARTNUM*"
			(at 0.02032 4.024884 180)
			(unlocked yes)
			(layer "Cmts.User")
			(hide yes)
			(effects
				(font
					(size 0.7874 0.5842)
					(thickness 0.1524)
				)
			)
		)
		(property "Device Type" "RESISTOR-G155-133R0-01,33OHM,1%"
			(at 0.008382 1.210564 180)
			(unlocked yes)
			(layer "F.Fab")
			(hide yes)
			(effects
				(font
					(size 0.7874 0.5842)
					(thickness 0.1524)
				)
			)
		)
		(duplicate_pad_numbers_are_jumpers no)
		(fp_line
			(start 1.143 0.5588)
			(end 1.143 -0.5588)
			(stroke
				(width 0.1)
				(type default)
			)
			(layer "F.SilkS")
		)
		(fp_line
			(start 1.143 -0.5588)
			(end -1.143 -0.5588)
			(stroke
				(width 0.1)
				(type default)
			)
			(layer "F.SilkS")
		)
		(fp_line
			(start -1.143 0.5588)
			(end 1.143 0.5588)
			(stroke
				(width 0.1)
				(type default)
			)
			(layer "F.SilkS")
		)
		(fp_line
			(start -1.143 -0.5588)
			(end -1.143 0.5588)
			(stroke
				(width 0.1)
				(type default)
			)
			(layer "F.SilkS")
		)
		(fp_rect
			(start -1.143 -0.5588)
			(end 1.143 0.5588)
			(stroke
				(width 0)
				(type default)
			)
			(fill no)
			(layer "F.CrtYd")
		)
		(fp_line
			(start 0.508 0.3048)
			(end 0.508 -0.3048)
			(stroke
				(width 0.1)
				(type default)
			)
			(layer "F.Fab")
		)
		(fp_line
			(start 0.508 -0.3048)
			(end -0.508 -0.3048)
			(stroke
				(width 0.1)
				(type default)
			)
			(layer "F.Fab")
		)
		(fp_line
			(start -0.508 0.3048)
			(end 0.508 0.3048)
			(stroke
				(width 0.1)
				(type default)
			)
			(layer "F.Fab")
		)
		(fp_line
			(start -0.508 -0.3048)
			(end -0.508 0.3048)
			(stroke
				(width 0.1)
				(type default)
			)
			(layer "F.Fab")
		)
		(pad "1" smd rect
			(at -0.5334 0 180)
			(size 0.7112 0.6096)
			(layers "F.Cu" "F.Mask" "F.Paste")
			(net "SMA2_LED_BLUE_N")
		)
		(pad "2" smd rect
			(at 0.5334 0 180)
			(size 0.7112 0.6096)
			(layers "F.Cu" "F.Mask" "F.Paste")
			(net "UNNAMED_14_LED4PV14_I266_1")
		)
		(zone
			(layer "F.Cu")
			(hatch none 0.5)
			(connect_pads
				(clearance 0)
			)
			(min_thickness 0.25)
			(keepout
				(tracks not_allowed)
				(vias allowed)
				(pads allowed)
				(copperpour not_allowed)
				(footprints allowed)
			)
			(placement
				(enabled no)
				(sheetname "")
			)
			(fill
				(thermal_gap 0.5)
				(thermal_bridge_width 0.5)
				(island_removal_mode 0)
			)
			(polygon
				(pts
					(xy 20.3962 -26.3652) (xy 20.3962 -26.9748) (xy 20.2438 -26.9748) (xy 20.2438 -26.3652)
				)
			)
		)
		(zone
			(layer "F.Cu")
			(hatch none 0.5)
			(connect_pads
				(clearance 0)
			)
			(min_thickness 0.25)
			(keepout
				(tracks allowed)
				(vias not_allowed)
				(pads allowed)
				(copperpour not_allowed)
				(footprints allowed)
			)
			(placement
				(enabled no)
				(sheetname "")
			)
			(fill
				(thermal_gap 0.5)
				(thermal_bridge_width 0.5)
				(island_removal_mode 0)
			)
			(polygon
				(pts
					(xy 20.3962 -26.3652) (xy 20.3962 -26.9748) (xy 20.2438 -26.9748) (xy 20.2438 -26.3652)
				)
			)
		)
	)
)
